(kicad_pcb
	(version 20260206)
	(generator "pcbnew")
	(generator_version "10.0")
	(general
		(thickness 1.6)
		(legacy_teardrops no)
	)
	(paper "A4")
	(title_block
		(title "04192023_DAF0TMB3IC0_F0TG_MB_C_brd_V02_OCP.brd")
		(comment 1 "Grand Teton / footprints 6116-6123 of 8354")
	)
	(layers
		(0 "F.Cu" signal "TOP")
		(4 "In1.Cu" signal "GND")
		(6 "In2.Cu" signal "IN1")
		(8 "In3.Cu" signal "GND1")
		(10 "In4.Cu" signal "IN2")
		(12 "In5.Cu" signal "GND2")
		(14 "In6.Cu" signal "IN3")
		(16 "In7.Cu" signal "GND3")
		(18 "In8.Cu" signal "VCC")
		(20 "In9.Cu" signal "VCC1")
		(22 "In10.Cu" signal "GND4")
		(24 "In11.Cu" signal "IN4")
		(26 "In12.Cu" signal "GND5")
		(28 "In13.Cu" signal "IN5")
		(30 "In14.Cu" signal "GND6")
		(32 "In15.Cu" signal "IN6")
		(34 "In16.Cu" signal "GND7")
		(2 "B.Cu" signal "BOTTOM")
		(9 "F.Adhes" user "F.Adhesive")
		(11 "B.Adhes" user "B.Adhesive")
		(13 "F.Paste" user "Package Geometry/Pastemask Top")
		(15 "B.Paste" user "Package Geometry/Pastemask Bottom")
		(5 "F.SilkS" user "Ref Des/Silkscreen Top")
		(7 "B.SilkS" user "Ref Des/Silkscreen Bottom")
		(1 "F.Mask" user "Board Geometry/Soldermask Top")
		(3 "B.Mask" user "Board Geometry/Soldermask Bottom")
		(17 "Dwgs.User" user "User.Drawings")
		(19 "Cmts.User" user "User.Comments")
		(21 "Eco1.User" user "User.Eco1")
		(23 "Eco2.User" user "User.Eco2")
		(25 "Edge.Cuts" user "Board Geometry/Outline")
		(27 "Margin" user)
		(31 "F.CrtYd" user "Package Geometry/Place Bound Top")
		(29 "B.CrtYd" user "Package Geometry/Place Bound Bottom")
		(35 "F.Fab" user "Ref Des/Assembly Top")
		(33 "B.Fab" user "Ref Des/Assembly Bottom")
	)
	(footprint ""
		(layer "B.Cu")
		(at 98.578924 -257.930396 180)
		(property "Reference" "C2123"
			(at 0 0 0)
			(layer "B.SilkS")
			(hide yes)
			(effects
				(font
					(size 1.27 1.27)
				)
				(justify mirror)
			)
		)
		(property "Value" ""
			(at 0 0 0)
			(layer "B.Fab")
			(effects
				(font
					(size 1.27 1.27)
				)
				(justify mirror)
			)
		)
		(duplicate_pad_numbers_are_jumpers no)
		(fp_line
			(start 0.7874 0.4064)
			(end 0.7874 -0.4064)
			(stroke
				(width 0.1524)
				(type default)
			)
			(layer "B.SilkS")
		)
		(fp_line
			(start 0.7874 -0.4064)
			(end -0.7874 -0.4064)
			(stroke
				(width 0.1524)
				(type default)
			)
			(layer "B.SilkS")
		)
		(fp_line
			(start -0.7874 0.4064)
			(end 0.7874 0.4064)
			(stroke
				(width 0.1524)
				(type default)
			)
			(layer "B.SilkS")
		)
		(fp_line
			(start -0.7874 -0.4064)
			(end -0.7874 0.4064)
			(stroke
				(width 0.1524)
				(type default)
			)
			(layer "B.SilkS")
		)
		(fp_line
			(start 0.67945 0.3048)
			(end 0.67945 -0.305054)
			(stroke
				(width 0.1)
				(type default)
			)
			(layer "B.Fab")
		)
		(fp_line
			(start 0.67945 -0.305054)
			(end 0.12065 -0.305054)
			(stroke
				(width 0.1)
				(type default)
			)
			(layer "B.Fab")
		)
		(fp_line
			(start 0.12065 0.3048)
			(end 0.67945 0.3048)
			(stroke
				(width 0.1)
				(type default)
			)
			(layer "B.Fab")
		)
		(fp_line
			(start 0.12065 0.2794)
			(end 0.12065 0.3048)
			(stroke
				(width 0.1)
				(type default)
			)
			(layer "B.Fab")
		)
		(fp_line
			(start 0.12065 -0.2794)
			(end -0.12065 -0.2794)
			(stroke
				(width 0.1)
				(type default)
			)
			(layer "B.Fab")
		)
		(fp_line
			(start 0.12065 -0.305054)
			(end 0.12065 -0.2794)
			(stroke
				(width 0.1)
				(type default)
			)
			(layer "B.Fab")
		)
		(fp_line
			(start -0.120396 0.3048)
			(end -0.120396 0.2794)
			(stroke
				(width 0.1)
				(type default)
			)
			(layer "B.Fab")
		)
		(fp_line
			(start -0.120396 0.2794)
			(end 0.12065 0.2794)
			(stroke
				(width 0.1)
				(type default)
			)
			(layer "B.Fab")
		)
		(fp_line
			(start -0.12065 -0.2794)
			(end -0.12065 -0.3048)
			(stroke
				(width 0.1)
				(type default)
			)
			(layer "B.Fab")
		)
		(fp_line
			(start -0.12065 -0.3048)
			(end -0.67945 -0.3048)
			(stroke
				(width 0.1)
				(type default)
			)
			(layer "B.Fab")
		)
		(fp_line
			(start -0.67945 0.3048)
			(end -0.120396 0.3048)
			(stroke
				(width 0.1)
				(type default)
			)
			(layer "B.Fab")
		)
		(fp_line
			(start -0.67945 -0.3048)
			(end -0.67945 0.3048)
			(stroke
				(width 0.1)
				(type default)
			)
			(layer "B.Fab")
		)
		(pad "1" smd circle
			(at 0.40005 0)
			(size 0 0)
			(layers "B.Cu" "B.Mask" "B.Paste")
			(net "PVDDIO_P1")
		)
		(pad "2" smd circle
			(at -0.40005 0)
			(size 0 0)
			(layers "B.Cu" "B.Mask" "B.Paste")
			(net "GND")
		)
	)
	(footprint ""
		(layer "B.Cu")
		(at 153.357834 -199.234552 90)
		(property "Reference" "R523"
			(at 0 0 90)
			(layer "B.SilkS")
			(hide yes)
			(effects
				(font
					(size 1.27 1.27)
				)
				(justify mirror)
			)
		)
		(property "Value" ""
			(at 0 0 90)
			(layer "B.Fab")
			(effects
				(font
					(size 1.27 1.27)
				)
				(justify mirror)
			)
		)
		(duplicate_pad_numbers_are_jumpers no)
		(fp_line
			(start 0.7874 -0.4064)
			(end -0.7874 -0.4064)
			(stroke
				(width 0.1524)
				(type default)
			)
			(layer "B.SilkS")
		)
		(fp_line
			(start -0.7874 -0.4064)
			(end -0.7874 0.4064)
			(stroke
				(width 0.1524)
				(type default)
			)
			(layer "B.SilkS")
		)
		(fp_line
			(start 0.7874 0.4064)
			(end 0.7874 -0.4064)
			(stroke
				(width 0.1524)
				(type default)
			)
			(layer "B.SilkS")
		)
		(fp_line
			(start -0.7874 0.4064)
			(end 0.7874 0.4064)
			(stroke
				(width 0.1524)
				(type default)
			)
			(layer "B.SilkS")
		)
		(fp_line
			(start 0.67945 -0.305054)
			(end 0.12065 -0.305054)
			(stroke
				(width 0.1)
				(type default)
			)
			(layer "B.Fab")
		)
		(fp_line
			(start 0.12065 -0.305054)
			(end 0.12065 -0.2794)
			(stroke
				(width 0.1)
				(type default)
			)
			(layer "B.Fab")
		)
		(fp_line
			(start -0.12065 -0.3048)
			(end -0.67945 -0.3048)
			(stroke
				(width 0.1)
				(type default)
			)
			(layer "B.Fab")
		)
		(fp_line
			(start -0.67945 -0.3048)
			(end -0.67945 0.3048)
			(stroke
				(width 0.1)
				(type default)
			)
			(layer "B.Fab")
		)
		(fp_line
			(start 0.12065 -0.2794)
			(end -0.12065 -0.2794)
			(stroke
				(width 0.1)
				(type default)
			)
			(layer "B.Fab")
		)
		(fp_line
			(start -0.12065 -0.2794)
			(end -0.12065 -0.3048)
			(stroke
				(width 0.1)
				(type default)
			)
			(layer "B.Fab")
		)
		(fp_line
			(start 0.12065 0.2794)
			(end 0.12065 0.3048)
			(stroke
				(width 0.1)
				(type default)
			)
			(layer "B.Fab")
		)
		(fp_line
			(start -0.120396 0.2794)
			(end 0.12065 0.2794)
			(stroke
				(width 0.1)
				(type default)
			)
			(layer "B.Fab")
		)
		(fp_line
			(start 0.67945 0.3048)
			(end 0.67945 -0.305054)
			(stroke
				(width 0.1)
				(type default)
			)
			(layer "B.Fab")
		)
		(fp_line
			(start 0.12065 0.3048)
			(end 0.67945 0.3048)
			(stroke
				(width 0.1)
				(type default)
			)
			(layer "B.Fab")
		)
		(fp_line
			(start -0.120396 0.3048)
			(end -0.120396 0.2794)
			(stroke
				(width 0.1)
				(type default)
			)
			(layer "B.Fab")
		)
		(fp_line
			(start -0.67945 0.3048)
			(end -0.120396 0.3048)
			(stroke
				(width 0.1)
				(type default)
			)
			(layer "B.Fab")
		)
		(pad "1" smd circle
			(at 0.40005 0 270)
			(size 0 0)
			(layers "B.Cu" "B.Mask" "B.Paste")
			(net "PVDD18_S5_P1")
		)
		(pad "2" smd circle
			(at -0.40005 0 270)
			(size 0 0)
			(layers "B.Cu" "B.Mask" "B.Paste")
			(net "JTAG_CPU1_TDO")
		)
	)
	(footprint ""
		(layer "B.Cu")
		(at 217.678 -339.598 180)
		(property "Reference" "R6747"
			(at 0 0 0)
			(layer "B.SilkS")
			(hide yes)
			(effects
				(font
					(size 1.27 1.27)
				)
				(justify mirror)
			)
		)
		(property "Value" ""
			(at 0 0 0)
			(layer "B.Fab")
			(effects
				(font
					(size 1.27 1.27)
				)
				(justify mirror)
			)
		)
		(duplicate_pad_numbers_are_jumpers no)
		(fp_line
			(start 0.32512 0.175006)
			(end 0.32512 -0.175006)
			(stroke
				(width 0.1)
				(type default)
			)
			(layer "B.Fab")
		)
		(fp_line
			(start 0.32512 -0.175006)
			(end -0.32512 -0.175006)
			(stroke
				(width 0.1)
				(type default)
			)
			(layer "B.Fab")
		)
		(fp_line
			(start -0.32512 0.175006)
			(end 0.32512 0.175006)
			(stroke
				(width 0.1)
				(type default)
			)
			(layer "B.Fab")
		)
		(fp_line
			(start -0.32512 -0.175006)
			(end -0.32512 0.175006)
			(stroke
				(width 0.1)
				(type default)
			)
			(layer "B.Fab")
		)
		(pad "1" smd rect
			(at 0.2667 0)
			(size 0.3048 0.381)
			(layers "B.Cu" "B.Mask" "B.Paste")
			(net "SMB_RT_CPU1_P3_R_SCL")
		)
		(pad "2" smd rect
			(at -0.2667 0 180)
			(size 0.3048 0.381)
			(layers "B.Cu" "B.Mask" "B.Paste")
			(net "SMB_RT_CPU1_P3_SCL")
		)
	)
	(footprint ""
		(layer "B.Cu")
		(at 352.787712 -340.002368 90)
		(property "Reference" "PC119_6"
			(at 0 0 90)
			(layer "B.SilkS")
			(hide yes)
			(effects
				(font
					(size 1.27 1.27)
				)
				(justify mirror)
			)
		)
		(property "Value" ""
			(at 0 0 90)
			(layer "B.Fab")
			(effects
				(font
					(size 1.27 1.27)
				)
				(justify mirror)
			)
		)
		(duplicate_pad_numbers_are_jumpers no)
		(fp_line
			(start 1.524 -0.762)
			(end -1.524 -0.762)
			(stroke
				(width 0.1524)
				(type default)
			)
			(layer "B.SilkS")
		)
		(fp_line
			(start -1.524 -0.762)
			(end -1.524 0.762)
			(stroke
				(width 0.1524)
				(type default)
			)
			(layer "B.SilkS")
		)
		(fp_line
			(start 1.524 0.762)
			(end 1.524 -0.762)
			(stroke
				(width 0.1524)
				(type default)
			)
			(layer "B.SilkS")
		)
		(fp_line
			(start -1.524 0.762)
			(end 1.524 0.762)
			(stroke
				(width 0.1524)
				(type default)
			)
			(layer "B.SilkS")
		)
		(fp_line
			(start 1.1049 -0.724916)
			(end 1.1049 0.724916)
			(stroke
				(width 0.1)
				(type default)
			)
			(layer "B.Fab")
		)
		(fp_line
			(start -1.1049 -0.724916)
			(end 1.1049 -0.724916)
			(stroke
				(width 0.1)
				(type default)
			)
			(layer "B.Fab")
		)
		(fp_line
			(start 1.1049 0.724916)
			(end -1.1049 0.724916)
			(stroke
				(width 0.1)
				(type default)
			)
			(layer "B.Fab")
		)
		(fp_line
			(start -1.1049 0.724916)
			(end -1.1049 -0.724916)
			(stroke
				(width 0.1)
				(type default)
			)
			(layer "B.Fab")
		)
		(pad "1" smd rect
			(at 0.889 0 90)
			(size 1.016 1.27)
			(layers "B.Cu" "B.Mask" "B.Paste")
			(net "SW_P12V_AUX_PVDDCR_CPU1_P0_FLT")
		)
		(pad "2" smd rect
			(at -0.889 0 90)
			(size 1.016 1.27)
			(layers "B.Cu" "B.Mask" "B.Paste")
			(net "GND")
		)
	)
	(footprint ""
		(layer "B.Cu")
		(at 68.594224 -408.517344 90)
		(property "Reference" "C6673"
			(at 0 0 90)
			(layer "B.SilkS")
			(hide yes)
			(effects
				(font
					(size 1.27 1.27)
				)
				(justify mirror)
			)
		)
		(property "Value" ""
			(at 0 0 90)
			(layer "B.Fab")
			(effects
				(font
					(size 1.27 1.27)
				)
				(justify mirror)
			)
		)
		(duplicate_pad_numbers_are_jumpers no)
		(fp_line
			(start 0.299974 -0.150114)
			(end -0.299974 -0.150114)
			(stroke
				(width 0.1)
				(type default)
			)
			(layer "B.Fab")
		)
		(fp_line
			(start -0.299974 -0.150114)
			(end -0.299974 0.150114)
			(stroke
				(width 0.1)
				(type default)
			)
			(layer "B.Fab")
		)
		(fp_line
			(start 0.299974 0.150114)
			(end 0.299974 -0.150114)
			(stroke
				(width 0.1)
				(type default)
			)
			(layer "B.Fab")
		)
		(fp_line
			(start -0.299974 0.150114)
			(end 0.299974 0.150114)
			(stroke
				(width 0.1)
				(type default)
			)
			(layer "B.Fab")
		)
		(pad "1" smd rect
			(at 0.2667 0 270)
			(size 0.3048 0.381)
			(layers "B.Cu" "B.Mask" "B.Paste")
			(net "P5E_CPU1_P1_TX_BUF_C_DP<6>")
		)
		(pad "2" smd rect
			(at -0.2667 0 270)
			(size 0.3048 0.381)
			(layers "B.Cu" "B.Mask" "B.Paste")
			(net "P5E_CPU1_P1_TX_BUF_DP<6>")
		)
	)
	(footprint ""
		(layer "B.Cu")
		(at 346.639896 -335.092294 90)
		(property "Reference" "PC139_5"
			(at 0 0 90)
			(layer "B.SilkS")
			(hide yes)
			(effects
				(font
					(size 1.27 1.27)
				)
				(justify mirror)
			)
		)
		(property "Value" ""
			(at 0 0 90)
			(layer "B.Fab")
			(effects
				(font
					(size 1.27 1.27)
				)
				(justify mirror)
			)
		)
		(duplicate_pad_numbers_are_jumpers no)
		(fp_line
			(start 1.524 -0.762)
			(end -1.524 -0.762)
			(stroke
				(width 0.1524)
				(type default)
			)
			(layer "B.SilkS")
		)
		(fp_line
			(start -1.524 -0.762)
			(end -1.524 0.762)
			(stroke
				(width 0.1524)
				(type default)
			)
			(layer "B.SilkS")
		)
		(fp_line
			(start 1.524 0.762)
			(end 1.524 -0.762)
			(stroke
				(width 0.1524)
				(type default)
			)
			(layer "B.SilkS")
		)
		(fp_line
			(start -1.524 0.762)
			(end 1.524 0.762)
			(stroke
				(width 0.1524)
				(type default)
			)
			(layer "B.SilkS")
		)
		(fp_line
			(start 1.1049 -0.724916)
			(end 1.1049 0.724916)
			(stroke
				(width 0.1)
				(type default)
			)
			(layer "B.Fab")
		)
		(fp_line
			(start -1.1049 -0.724916)
			(end 1.1049 -0.724916)
			(stroke
				(width 0.1)
				(type default)
			)
			(layer "B.Fab")
		)
		(fp_line
			(start 1.1049 0.724916)
			(end -1.1049 0.724916)
			(stroke
				(width 0.1)
				(type default)
			)
			(layer "B.Fab")
		)
		(fp_line
			(start -1.1049 0.724916)
			(end -1.1049 -0.724916)
			(stroke
				(width 0.1)
				(type default)
			)
			(layer "B.Fab")
		)
		(pad "1" smd rect
			(at 0.889 0 90)
			(size 1.016 1.27)
			(layers "B.Cu" "B.Mask" "B.Paste")
			(net "SW_P12V_AUX_PVDDCR_CPU1_P0_FLT")
		)
		(pad "2" smd rect
			(at -0.889 0 90)
			(size 1.016 1.27)
			(layers "B.Cu" "B.Mask" "B.Paste")
			(net "GND")
		)
	)
	(footprint ""
		(layer "B.Cu")
		(at 408.597608 -327.866502 90)
		(property "Reference" "R5056"
			(at 0 0 90)
			(layer "B.SilkS")
			(hide yes)
			(effects
				(font
					(size 1.27 1.27)
				)
				(justify mirror)
			)
		)
		(property "Value" ""
			(at 0 0 90)
			(layer "B.Fab")
			(effects
				(font
					(size 1.27 1.27)
				)
				(justify mirror)
			)
		)
		(duplicate_pad_numbers_are_jumpers no)
		(fp_line
			(start 0.7874 -0.4064)
			(end -0.7874 -0.4064)
			(stroke
				(width 0.1524)
				(type default)
			)
			(layer "B.SilkS")
		)
		(fp_line
			(start -0.7874 -0.4064)
			(end -0.7874 0.4064)
			(stroke
				(width 0.1524)
				(type default)
			)
			(layer "B.SilkS")
		)
		(fp_line
			(start 0.7874 0.4064)
			(end 0.7874 -0.4064)
			(stroke
				(width 0.1524)
				(type default)
			)
			(layer "B.SilkS")
		)
		(fp_line
			(start -0.7874 0.4064)
			(end 0.7874 0.4064)
			(stroke
				(width 0.1524)
				(type default)
			)
			(layer "B.SilkS")
		)
		(fp_line
			(start 0.67945 -0.305054)
			(end 0.12065 -0.305054)
			(stroke
				(width 0.1)
				(type default)
			)
			(layer "B.Fab")
		)
		(fp_line
			(start 0.12065 -0.305054)
			(end 0.12065 -0.2794)
			(stroke
				(width 0.1)
				(type default)
			)
			(layer "B.Fab")
		)
		(fp_line
			(start -0.12065 -0.3048)
			(end -0.67945 -0.3048)
			(stroke
				(width 0.1)
				(type default)
			)
			(layer "B.Fab")
		)
		(fp_line
			(start -0.67945 -0.3048)
			(end -0.67945 0.3048)
			(stroke
				(width 0.1)
				(type default)
			)
			(layer "B.Fab")
		)
		(fp_line
			(start 0.12065 -0.2794)
			(end -0.12065 -0.2794)
			(stroke
				(width 0.1)
				(type default)
			)
			(layer "B.Fab")
		)
		(fp_line
			(start -0.12065 -0.2794)
			(end -0.12065 -0.3048)
			(stroke
				(width 0.1)
				(type default)
			)
			(layer "B.Fab")
		)
		(fp_line
			(start 0.12065 0.2794)
			(end 0.12065 0.3048)
			(stroke
				(width 0.1)
				(type default)
			)
			(layer "B.Fab")
		)
		(fp_line
			(start -0.120396 0.2794)
			(end 0.12065 0.2794)
			(stroke
				(width 0.1)
				(type default)
			)
			(layer "B.Fab")
		)
		(fp_line
			(start 0.67945 0.3048)
			(end 0.67945 -0.305054)
			(stroke
				(width 0.1)
				(type default)
			)
			(layer "B.Fab")
		)
		(fp_line
			(start 0.12065 0.3048)
			(end 0.67945 0.3048)
			(stroke
				(width 0.1)
				(type default)
			)
			(layer "B.Fab")
		)
		(fp_line
			(start -0.120396 0.3048)
			(end -0.120396 0.2794)
			(stroke
				(width 0.1)
				(type default)
			)
			(layer "B.Fab")
		)
		(fp_line
			(start -0.67945 0.3048)
			(end -0.120396 0.3048)
			(stroke
				(width 0.1)
				(type default)
			)
			(layer "B.Fab")
		)
		(pad "1" smd circle
			(at 0.40005 0 270)
			(size 0 0)
			(layers "B.Cu" "B.Mask" "B.Paste")
			(net "CPU0_RTC_LDO_SELECT")
		)
		(pad "2" smd circle
			(at -0.40005 0 270)
			(size 0 0)
			(layers "B.Cu" "B.Mask" "B.Paste")
			(net "GND")
		)
	)
	(footprint ""
		(layer "B.Cu")
		(at 415.471102 -244.08511)
		(property "Reference" "R381"
			(at 0 0 0)
			(layer "B.SilkS")
			(hide yes)
			(effects
				(font
					(size 1.27 1.27)
				)
				(justify mirror)
			)
		)
		(property "Value" ""
			(at 0 0 0)
			(layer "B.Fab")
			(effects
				(font
					(size 1.27 1.27)
				)
				(justify mirror)
			)
		)
		(duplicate_pad_numbers_are_jumpers no)
		(fp_line
			(start -0.7874 -0.4064)
			(end -0.7874 0.4064)
			(stroke
				(width 0.1524)
				(type default)
			)
			(layer "B.SilkS")
		)
		(fp_line
			(start -0.7874 0.4064)
			(end 0.7874 0.4064)
			(stroke
				(width 0.1524)
				(type default)
			)
			(layer "B.SilkS")
		)
		(fp_line
			(start 0.7874 -0.4064)
			(end -0.7874 -0.4064)
			(stroke
				(width 0.1524)
				(type default)
			)
			(layer "B.SilkS")
		)
		(fp_line
			(start 0.7874 0.4064)
			(end 0.7874 -0.4064)
			(stroke
				(width 0.1524)
				(type default)
			)
			(layer "B.SilkS")
		)
		(fp_line
			(start -0.67945 -0.3048)
			(end -0.67945 0.3048)
			(stroke
				(width 0.1)
				(type default)
			)
			(layer "B.Fab")
		)
		(fp_line
			(start -0.67945 0.3048)
			(end -0.120396 0.3048)
			(stroke
				(width 0.1)
				(type default)
			)
			(layer "B.Fab")
		)
		(fp_line
			(start -0.12065 -0.3048)
			(end -0.67945 -0.3048)
			(stroke
				(width 0.1)
				(type default)
			)
			(layer "B.Fab")
		)
		(fp_line
			(start -0.12065 -0.2794)
			(end -0.12065 -0.3048)
			(stroke
				(width 0.1)
				(type default)
			)
			(layer "B.Fab")
		)
		(fp_line
			(start -0.120396 0.2794)
			(end 0.12065 0.2794)
			(stroke
				(width 0.1)
				(type default)
			)
			(layer "B.Fab")
		)
		(fp_line
			(start -0.120396 0.3048)
			(end -0.120396 0.2794)
			(stroke
				(width 0.1)
				(type default)
			)
			(layer "B.Fab")
		)
		(fp_line
			(start 0.12065 -0.305054)
			(end 0.12065 -0.2794)
			(stroke
				(width 0.1)
				(type default)
			)
			(layer "B.Fab")
		)
		(fp_line
			(start 0.12065 -0.2794)
			(end -0.12065 -0.2794)
			(stroke
				(width 0.1)
				(type default)
			)
			(layer "B.Fab")
		)
		(fp_line
			(start 0.12065 0.2794)
			(end 0.12065 0.3048)
			(stroke
				(width 0.1)
				(type default)
			)
			(layer "B.Fab")
		)
		(fp_line
			(start 0.12065 0.3048)
			(end 0.67945 0.3048)
			(stroke
				(width 0.1)
				(type default)
			)
			(layer "B.Fab")
		)
		(fp_line
			(start 0.67945 -0.305054)
			(end 0.12065 -0.305054)
			(stroke
				(width 0.1)
				(type default)
			)
			(layer "B.Fab")
		)
		(fp_line
			(start 0.67945 0.3048)
			(end 0.67945 -0.305054)
			(stroke
				(width 0.1)
				(type default)
			)
			(layer "B.Fab")
		)
		(pad "1" smd circle
			(at 0.40005 0 180)
			(size 0 0)
			(layers "B.Cu" "B.Mask" "B.Paste")
			(net "M_G_CPU0_ALERT_N")
		)
		(pad "2" smd circle
			(at -0.40005 0 180)
			(size 0 0)
			(layers "B.Cu" "B.Mask" "B.Paste")
			(net "M_G_CPU0_ALERT_R_N")
		)
	)
)
